(kicad_pcb
	(version 20241229)
	(generator "pcbnew")
	(generator_version "9.0")
	(general
		(thickness 1.711)
		(legacy_teardrops no)
	)
	(paper "A4")
	(title_block
		(title "Antmicro Baseboard for Jetson AGX Thor")
		(date "2026-02-18")
		(rev "1.1.0")
		(company "Antmicro Ltd")
		(comment 1 "www.antmicro.com")
		(comment 9 "footprints 975-979 of 1170")
	)
	(layers
		(0 "F.Cu" signal)
		(4 "In1.Cu" signal)
		(6 "In2.Cu" signal)
		(8 "In3.Cu" signal)
		(10 "In4.Cu" jumper)
		(12 "In5.Cu" signal)
		(14 "In6.Cu" signal)
		(16 "In7.Cu" signal)
		(18 "In8.Cu" signal)
		(2 "B.Cu" signal)
		(9 "F.Adhes" user "F.Adhesive")
		(11 "B.Adhes" user "B.Adhesive")
		(13 "F.Paste" user)
		(15 "B.Paste" user)
		(5 "F.SilkS" user "F.Silkscreen")
		(7 "B.SilkS" user "B.Silkscreen")
		(1 "F.Mask" user)
		(3 "B.Mask" user)
		(17 "Dwgs.User" user "User.Drawings")
		(19 "Cmts.User" user "User.Comments")
		(21 "Eco1.User" user "User.Eco1")
		(23 "Eco2.User" user "User.Eco2")
		(25 "Edge.Cuts" user)
		(27 "Margin" user)
		(31 "F.CrtYd" user "F.Courtyard")
		(29 "B.CrtYd" user "B.Courtyard")
		(35 "F.Fab" user)
		(33 "B.Fab" user)
	)
	(footprint "antmicro-footprints:C_0402_1005Metric"
		(layer "B.Cu")
		(at 89.8 74.8 90)
		(descr "Capacitor SMD 0402")
		(tags "capacitor SMD 0402")
		(property "Reference" "C366"
			(at -0.9 0.7 90)
			(layer "B.SilkS")
			(effects
				(font
					(size 0.7 0.7)
					(thickness 0.15)
				)
				(justify right top mirror)
			)
		)
		(property "Value" "C_1u_25V_0402"
			(at -1.022927 -2.155213 90)
			(layer "B.Fab")
			(effects
				(font
					(size 0.7 0.7)
					(thickness 0.15)
				)
				(justify right top mirror)
			)
		)
		(property "Datasheet" "https://www.murata.com/products/productdetail?partno=GRM155R61E105KE11%23"
			(at 0 0 90)
			(layer "B.Fab")
			(hide yes)
			(effects
				(font
					(size 1.27 1.27)
					(thickness 0.15)
				)
				(justify mirror)
			)
		)
		(property "Description" "SMD Multilayer Ceramic Capacitor, 1 µF, 25 V, 0402 [1005 Metric], ± 10%, X5R, GRM Series"
			(at 0 0 90)
			(layer "B.Fab")
			(hide yes)
			(effects
				(font
					(size 1.27 1.27)
					(thickness 0.15)
				)
				(justify mirror)
			)
		)
		(property "MPN" "GRM155R61E105KE11J"
			(at 0 0 270)
			(unlocked yes)
			(layer "B.Fab")
			(hide yes)
			(effects
				(font
					(size 1 1)
					(thickness 0.15)
				)
				(justify mirror)
			)
		)
		(property "Manufacturer" "Murata"
			(at 0 0 270)
			(unlocked yes)
			(layer "B.Fab")
			(hide yes)
			(effects
				(font
					(size 1 1)
					(thickness 0.15)
				)
				(justify mirror)
			)
		)
		(property "License" "Apache-2.0"
			(at 0 0 270)
			(unlocked yes)
			(layer "B.Fab")
			(hide yes)
			(effects
				(font
					(size 1 1)
					(thickness 0.15)
				)
				(justify mirror)
			)
		)
		(property "Author" "Antmicro"
			(at 0 0 270)
			(unlocked yes)
			(layer "B.Fab")
			(hide yes)
			(effects
				(font
					(size 1 1)
					(thickness 0.15)
				)
				(justify mirror)
			)
		)
		(property "Val" "1u"
			(at 0 0 270)
			(unlocked yes)
			(layer "B.Fab")
			(hide yes)
			(effects
				(font
					(size 1 1)
					(thickness 0.15)
				)
				(justify mirror)
			)
		)
		(property "Voltage" "25V"
			(at 0 0 270)
			(unlocked yes)
			(layer "B.Fab")
			(hide yes)
			(effects
				(font
					(size 1 1)
					(thickness 0.15)
				)
				(justify mirror)
			)
		)
		(property "Dielectric" "X5R"
			(at 0 0 270)
			(unlocked yes)
			(layer "B.Fab")
			(hide yes)
			(effects
				(font
					(size 1 1)
					(thickness 0.15)
				)
				(justify mirror)
			)
		)
		(sheetname "/SoM_Power/")
		(sheetfile "som_power.kicad_sch")
		(attr smd)
		(fp_poly
			(pts
				(xy -0.925 0.47) (xy 0.925 0.47) (xy 0.925 -0.47) (xy -0.925 -0.47)
			)
			(stroke
				(width 0.05)
				(type default)
			)
			(fill no)
			(layer "B.CrtYd")
		)
		(fp_line
			(start 0.504 -0.248)
			(end -0.494 -0.248)
			(stroke
				(width 0.15)
				(type solid)
			)
			(layer "B.Fab")
		)
		(fp_line
			(start -0.494 -0.248)
			(end -0.494 0.25)
			(stroke
				(width 0.15)
				(type solid)
			)
			(layer "B.Fab")
		)
		(fp_line
			(start 0.504 0.25)
			(end 0.504 -0.248)
			(stroke
				(width 0.15)
				(type solid)
			)
			(layer "B.Fab")
		)
		(fp_line
			(start -0.494 0.25)
			(end 0.504 0.25)
			(stroke
				(width 0.15)
				(type solid)
			)
			(layer "B.Fab")
		)
		(fp_text user "Author: Antmicro"
			(at -0.939 -3.399 90)
			(layer "B.Fab")
			(effects
				(font
					(size 0.7 0.7)
					(thickness 0.15)
				)
				(justify right top mirror)
			)
		)
		(fp_text user "${REFERENCE}"
			(at -0.939 -4.599 90)
			(layer "B.Fab")
			(effects
				(font
					(size 0.7 0.7)
					(thickness 0.15)
				)
				(justify right top mirror)
			)
		)
		(fp_text user "License: Apache-2.0"
			(at -0.939 -5.799 90)
			(layer "B.Fab")
			(effects
				(font
					(size 0.7 0.7)
					(thickness 0.15)
				)
				(justify right top mirror)
			)
		)
		(pad "1" smd roundrect
			(at -0.48 0 90)
			(size 0.59 0.64)
			(layers "B.Cu" "B.Mask" "B.Paste")
			(roundrect_rratio 0.25)
			(net 1 "GND")
			(pintype "passive")
		)
		(pad "2" smd roundrect
			(at 0.48 0 90)
			(size 0.59 0.64)
			(layers "B.Cu" "B.Mask" "B.Paste")
			(roundrect_rratio 0.25)
			(net 12 "SYS_VIN_HV")
			(pintype "passive")
		)
	)
	(footprint "antmicro-footprints:R_0402_1005Metric"
		(layer "B.Cu")
		(at 143.8 71.7 -90)
		(descr "Resistor SMD 0402")
		(tags "resistor SMD 0402")
		(property "Reference" "R291"
			(at -1 -2.5 90)
			(layer "B.SilkS")
			(effects
				(font
					(size 0.7 0.7)
					(thickness 0.15)
				)
				(justify left bottom mirror)
			)
		)
		(property "Value" "R_0R_0402"
			(at -1.011843 -1.772047 90)
			(layer "B.Fab")
			(effects
				(font
					(size 0.7 0.7)
					(thickness 0.15)
				)
				(justify left bottom mirror)
			)
		)
		(property "Datasheet" "https://industrial.panasonic.com/cdbs/www-data/pdf/RDA0000/AOA0000C301.pdf"
			(at 0 0 90)
			(layer "B.Fab")
			(hide yes)
			(effects
				(font
					(size 1.27 1.27)
					(thickness 0.15)
				)
				(justify mirror)
			)
		)
		(property "Description" "SMD Chip Resistor, Jumper, 0 ohm, 100 mW, 0402 [1005 Metric], Thick Film, General Purpose"
			(at 0 0 90)
			(layer "B.Fab")
			(hide yes)
			(effects
				(font
					(size 1.27 1.27)
					(thickness 0.15)
				)
				(justify mirror)
			)
		)
		(property "MPN" "ERJ2GE0R00X"
			(at 0 0 90)
			(unlocked yes)
			(layer "B.Fab")
			(hide yes)
			(effects
				(font
					(size 1 1)
					(thickness 0.15)
				)
				(justify mirror)
			)
		)
		(property "Manufacturer" "Panasonic"
			(at 0 0 90)
			(unlocked yes)
			(layer "B.Fab")
			(hide yes)
			(effects
				(font
					(size 1 1)
					(thickness 0.15)
				)
				(justify mirror)
			)
		)
		(property "License" "Apache-2.0"
			(at 0 0 90)
			(unlocked yes)
			(layer "B.Fab")
			(hide yes)
			(effects
				(font
					(size 1 1)
					(thickness 0.15)
				)
				(justify mirror)
			)
		)
		(property "Author" "Antmicro"
			(at 0 0 90)
			(unlocked yes)
			(layer "B.Fab")
			(hide yes)
			(effects
				(font
					(size 1 1)
					(thickness 0.15)
				)
				(justify mirror)
			)
		)
		(property "Val" "0R"
			(at 0 0 90)
			(unlocked yes)
			(layer "B.Fab")
			(hide yes)
			(effects
				(font
					(size 1 1)
					(thickness 0.15)
				)
				(justify mirror)
			)
		)
		(property "Tolerance" "~"
			(at 0 0 90)
			(unlocked yes)
			(layer "B.Fab")
			(hide yes)
			(effects
				(font
					(size 1 1)
					(thickness 0.15)
				)
				(justify mirror)
			)
		)
		(property "Current" "1A"
			(at 0 0 90)
			(unlocked yes)
			(layer "B.Fab")
			(hide yes)
			(effects
				(font
					(size 1 1)
					(thickness 0.15)
				)
				(justify mirror)
			)
		)
		(sheetname "/SoM_IO2/")
		(sheetfile "som_io2.kicad_sch")
		(attr smd exclude_from_pos_files exclude_from_bom dnp)
		(fp_rect
			(start -0.925 0.47)
			(end 0.925 -0.47)
			(stroke
				(width 0.05)
				(type default)
			)
			(fill no)
			(layer "B.CrtYd")
		)
		(fp_rect
			(start -0.5 0.25)
			(end 0.5 -0.25)
			(stroke
				(width 0.15)
				(type solid)
			)
			(fill no)
			(layer "B.Fab")
		)
		(fp_text user "License: Apache-2.0"
			(at -0.95 -5.169 90)
			(layer "B.Fab")
			(effects
				(font
					(size 0.7 0.7)
					(thickness 0.15)
				)
				(justify left bottom mirror)
			)
		)
		(fp_text user "${REFERENCE}"
			(at -0.95 -3.168 90)
			(layer "B.Fab")
			(effects
				(font
					(size 0.7 0.7)
					(thickness 0.15)
				)
				(justify left bottom mirror)
			)
		)
		(fp_text user "Author: Antmicro"
			(at -0.95 -4.169 90)
			(layer "B.Fab")
			(effects
				(font
					(size 0.7 0.7)
					(thickness 0.15)
				)
				(justify left bottom mirror)
			)
		)
		(pad "1" smd roundrect
			(at -0.48 0 270)
			(size 0.59 0.64)
			(layers "B.Cu" "B.Mask" "B.Paste")
			(roundrect_rratio 0.25)
			(net 11 "+1V8")
			(pintype "passive")
		)
		(pad "2" smd roundrect
			(at 0.48 0 270)
			(size 0.59 0.64)
			(layers "B.Cu" "B.Mask" "B.Paste")
			(roundrect_rratio 0.25)
			(net 652 "/SoM_IO2/NVDBG_SEL")
			(pintype "passive")
		)
	)
	(footprint "antmicro-footprints:R_0402_1005Metric"
		(layer "B.Cu")
		(at 71.1 66.3)
		(descr "Resistor SMD 0402")
		(tags "resistor SMD 0402")
		(property "Reference" "R396"
			(at 0.9 -0.3 0)
			(layer "B.SilkS")
			(effects
				(font
					(size 0.7 0.7)
					(thickness 0.15)
				)
				(justify right top mirror)
			)
		)
		(property "Value" "R_0R_0402"
			(at -1.011843 -1.772047 0)
			(layer "B.Fab")
			(effects
				(font
					(size 0.7 0.7)
					(thickness 0.15)
				)
				(justify right top mirror)
			)
		)
		(property "Datasheet" "https://industrial.panasonic.com/cdbs/www-data/pdf/RDA0000/AOA0000C301.pdf"
			(at 0 0 0)
			(layer "B.Fab")
			(hide yes)
			(effects
				(font
					(size 1.27 1.27)
					(thickness 0.15)
				)
				(justify mirror)
			)
		)
		(property "Description" "SMD Chip Resistor, Jumper, 0 ohm, 100 mW, 0402 [1005 Metric], Thick Film, General Purpose"
			(at 0 0 0)
			(layer "B.Fab")
			(hide yes)
			(effects
				(font
					(size 1.27 1.27)
					(thickness 0.15)
				)
				(justify mirror)
			)
		)
		(property "MPN" "ERJ2GE0R00X"
			(at 0 0 180)
			(unlocked yes)
			(layer "B.Fab")
			(hide yes)
			(effects
				(font
					(size 1 1)
					(thickness 0.15)
				)
				(justify mirror)
			)
		)
		(property "Manufacturer" "Panasonic"
			(at 0 0 180)
			(unlocked yes)
			(layer "B.Fab")
			(hide yes)
			(effects
				(font
					(size 1 1)
					(thickness 0.15)
				)
				(justify mirror)
			)
		)
		(property "License" "Apache-2.0"
			(at 0 0 180)
			(unlocked yes)
			(layer "B.Fab")
			(hide yes)
			(effects
				(font
					(size 1 1)
					(thickness 0.15)
				)
				(justify mirror)
			)
		)
		(property "Author" "Antmicro"
			(at 0 0 180)
			(unlocked yes)
			(layer "B.Fab")
			(hide yes)
			(effects
				(font
					(size 1 1)
					(thickness 0.15)
				)
				(justify mirror)
			)
		)
		(property "Val" "0R"
			(at 0 0 180)
			(unlocked yes)
			(layer "B.Fab")
			(hide yes)
			(effects
				(font
					(size 1 1)
					(thickness 0.15)
				)
				(justify mirror)
			)
		)
		(property "Tolerance" "~"
			(at 0 0 180)
			(unlocked yes)
			(layer "B.Fab")
			(hide yes)
			(effects
				(font
					(size 1 1)
					(thickness 0.15)
				)
				(justify mirror)
			)
		)
		(property "Current" "1A"
			(at 0 0 180)
			(unlocked yes)
			(layer "B.Fab")
			(hide yes)
			(effects
				(font
					(size 1 1)
					(thickness 0.15)
				)
				(justify mirror)
			)
		)
		(sheetname "/CSI/")
		(sheetfile "csi.kicad_sch")
		(attr smd)
		(fp_rect
			(start -0.925 0.47)
			(end 0.925 -0.47)
			(stroke
				(width 0.05)
				(type default)
			)
			(fill no)
			(layer "B.CrtYd")
		)
		(fp_rect
			(start -0.5 0.25)
			(end 0.5 -0.25)
			(stroke
				(width 0.15)
				(type solid)
			)
			(fill no)
			(layer "B.Fab")
		)
		(fp_text user "Author: Antmicro"
			(at -0.95 -4.169 0)
			(layer "B.Fab")
			(effects
				(font
					(size 0.7 0.7)
					(thickness 0.15)
				)
				(justify right top mirror)
			)
		)
		(fp_text user "${REFERENCE}"
			(at -0.95 -3.168 0)
			(layer "B.Fab")
			(effects
				(font
					(size 0.7 0.7)
					(thickness 0.15)
				)
				(justify right top mirror)
			)
		)
		(fp_text user "License: Apache-2.0"
			(at -0.95 -5.169 0)
			(layer "B.Fab")
			(effects
				(font
					(size 0.7 0.7)
					(thickness 0.15)
				)
				(justify right top mirror)
			)
		)
		(pad "1" smd roundrect
			(at -0.48 0)
			(size 0.59 0.64)
			(layers "B.Cu" "B.Mask" "B.Paste")
			(roundrect_rratio 0.25)
			(net 994 "/CSI/SCL_CAM2")
			(pintype "passive")
		)
		(pad "2" smd roundrect
			(at 0.48 0)
			(size 0.59 0.64)
			(layers "B.Cu" "B.Mask" "B.Paste")
			(roundrect_rratio 0.25)
			(net 1372 "Net-(J10-Pad40)")
			(pintype "passive")
		)
	)
	(footprint "antmicro-footprints:C_0603_1608Metric_EIA"
		(layer "B.Cu")
		(at 115.55 69.46 180)
		(descr "Capacitor SMD 0603, IPC-7351 Density Level A")
		(tags "Capacitor 0603")
		(property "Reference" "C23"
			(at -1.05 0.86 0)
			(layer "B.SilkS")
			(effects
				(font
					(size 0.7 0.7)
					(thickness 0.15)
				)
				(justify left bottom mirror)
			)
		)
		(property "Value" "C_22u_16V_0603"
			(at -1.42757 -1.770288 0)
			(layer "B.Fab")
			(effects
				(font
					(size 0.7 0.7)
					(thickness 0.15)
				)
				(justify left bottom mirror)
			)
		)
		(property "Datasheet" "https://product.samsungsem.com/mlcc/CL10A226MO7JZN.do"
			(at 0 0 0)
			(layer "B.Fab")
			(hide yes)
			(effects
				(font
					(size 1.27 1.27)
					(thickness 0.15)
				)
				(justify mirror)
			)
		)
		(property "Description" "SMD Multilayer Ceramic Capacitor"
			(at 0 0 0)
			(layer "B.Fab")
			(hide yes)
			(effects
				(font
					(size 1.27 1.27)
					(thickness 0.15)
				)
				(justify mirror)
			)
		)
		(property "MPN" "CL10A226MO7JZNC"
			(at 0 0 180)
			(unlocked yes)
			(layer "B.Fab")
			(hide yes)
			(effects
				(font
					(size 1 1)
					(thickness 0.15)
				)
				(justify mirror)
			)
		)
		(property "Manufacturer" "Samsung Electro-Mechanics"
			(at 0 0 180)
			(unlocked yes)
			(layer "B.Fab")
			(hide yes)
			(effects
				(font
					(size 1 1)
					(thickness 0.15)
				)
				(justify mirror)
			)
		)
		(property "License" "Apache-2.0"
			(at 0 0 180)
			(unlocked yes)
			(layer "B.Fab")
			(hide yes)
			(effects
				(font
					(size 1 1)
					(thickness 0.15)
				)
				(justify mirror)
			)
		)
		(property "Author" "Antmicro"
			(at 0 0 180)
			(unlocked yes)
			(layer "B.Fab")
			(hide yes)
			(effects
				(font
					(size 1 1)
					(thickness 0.15)
				)
				(justify mirror)
			)
		)
		(property "Val" "22u"
			(at 0 0 180)
			(unlocked yes)
			(layer "B.Fab")
			(hide yes)
			(effects
				(font
					(size 1 1)
					(thickness 0.15)
				)
				(justify mirror)
			)
		)
		(property "Voltage" "16V"
			(at 0 0 180)
			(unlocked yes)
			(layer "B.Fab")
			(hide yes)
			(effects
				(font
					(size 1 1)
					(thickness 0.15)
				)
				(justify mirror)
			)
		)
		(property "Dielectric" "X7R"
			(at 0 0 180)
			(unlocked yes)
			(layer "B.Fab")
			(hide yes)
			(effects
				(font
					(size 1 1)
					(thickness 0.15)
				)
				(justify mirror)
			)
		)
		(property "Public" "False"
			(at 0 0 180)
			(unlocked yes)
			(layer "B.Fab")
			(hide yes)
			(effects
				(font
					(size 1 1)
					(thickness 0.15)
				)
				(justify mirror)
			)
		)
		(sheetname "/SoM_Power/")
		(sheetfile "som_power.kicad_sch")
		(attr smd)
		(fp_line
			(start -0.15 0.55)
			(end 0.15 0.55)
			(stroke
				(width 0.15)
				(type solid)
			)
			(layer "B.SilkS")
		)
		(fp_line
			(start -0.15 -0.55)
			(end 0.15 -0.55)
			(stroke
				(width 0.15)
				(type solid)
			)
			(layer "B.SilkS")
		)
		(fp_rect
			(start -1.25 0.65)
			(end 1.25 -0.65)
			(stroke
				(width 0.05)
				(type solid)
			)
			(fill no)
			(layer "B.CrtYd")
		)
		(fp_rect
			(start -0.8 0.45)
			(end 0.8 -0.45)
			(stroke
				(width 0.15)
				(type solid)
			)
			(fill no)
			(layer "B.Fab")
		)
		(fp_text user "License: Apache-2.0"
			(at -1.682 -5.895 0)
			(layer "B.Fab")
			(effects
				(font
					(size 0.7 0.7)
					(thickness 0.15)
				)
				(justify left bottom mirror)
			)
		)
		(fp_text user "Author: Antmicro"
			(at -1.682 -4.894 0)
			(layer "B.Fab")
			(effects
				(font
					(size 0.7 0.7)
					(thickness 0.15)
				)
				(justify left bottom mirror)
			)
		)
		(fp_text user "${REFERENCE}"
			(at -1.682 -3.895 0)
			(layer "B.Fab")
			(effects
				(font
					(size 0.7 0.7)
					(thickness 0.15)
				)
				(justify left bottom mirror)
			)
		)
		(pad "1" smd roundrect
			(at -0.7 0 180)
			(size 0.8 1.1)
			(layers "B.Cu" "B.Mask" "B.Paste")
			(roundrect_rratio 0.2)
			(net 1 "GND")
			(pintype "passive")
		)
		(pad "2" smd roundrect
			(at 0.7 0 180)
			(size 0.8 1.1)
			(layers "B.Cu" "B.Mask" "B.Paste")
			(roundrect_rratio 0.2)
			(net 213 "+5V_SOM")
			(pintype "passive")
		)
	)
	(footprint "antmicro-footprints:R_0402_1005Metric"
		(layer "B.Cu")
		(at 220.426 152.2)
		(descr "Resistor SMD 0402")
		(tags "resistor SMD 0402")
		(property "Reference" "R200"
			(at -1.8 -1.5 0)
			(layer "B.SilkS")
			(effects
				(font
					(size 0.7 0.7)
					(thickness 0.15)
				)
				(justify right top mirror)
			)
		)
		(property "Value" "R_330R_0402"
			(at -1.011843 -1.772046 0)
			(layer "B.Fab")
			(effects
				(font
					(size 0.7 0.7)
					(thickness 0.15)
				)
				(justify right top mirror)
			)
		)
		(property "Datasheet" "https://www.bourns.com/docs/product-datasheets/cr.pdf"
			(at 0 0 0)
			(layer "B.Fab")
			(hide yes)
			(effects
				(font
					(size 1.27 1.27)
					(thickness 0.15)
				)
				(justify mirror)
			)
		)
		(property "Description" "SMD Chip Resistor, 330 ohm, ± 1%, 62.5 mW, 0402 [1005 Metric], Thick Film, General Purpose"
			(at 0 0 0)
			(layer "B.Fab")
			(hide yes)
			(effects
				(font
					(size 1.27 1.27)
					(thickness 0.15)
				)
				(justify mirror)
			)
		)
		(property "MPN" "CR0402-FX-3300GLF"
			(at 0 0 180)
			(unlocked yes)
			(layer "B.Fab")
			(hide yes)
			(effects
				(font
					(size 1 1)
					(thickness 0.15)
				)
				(justify mirror)
			)
		)
		(property "Manufacturer" "Bourns"
			(at 0 0 180)
			(unlocked yes)
			(layer "B.Fab")
			(hide yes)
			(effects
				(font
					(size 1 1)
					(thickness 0.15)
				)
				(justify mirror)
			)
		)
		(property "License" "Apache-2.0"
			(at 0 0 180)
			(unlocked yes)
			(layer "B.Fab")
			(hide yes)
			(effects
				(font
					(size 1 1)
					(thickness 0.15)
				)
				(justify mirror)
			)
		)
		(property "Author" "Antmicro"
			(at 0 0 180)
			(unlocked yes)
			(layer "B.Fab")
			(hide yes)
			(effects
				(font
					(size 1 1)
					(thickness 0.15)
				)
				(justify mirror)
			)
		)
		(property "Val" "330R"
			(at 0 0 180)
			(unlocked yes)
			(layer "B.Fab")
			(hide yes)
			(effects
				(font
					(size 1 1)
					(thickness 0.15)
				)
				(justify mirror)
			)
		)
		(property "Tolerance" "1%"
			(at 0 0 180)
			(unlocked yes)
			(layer "B.Fab")
			(hide yes)
			(effects
				(font
					(size 1 1)
					(thickness 0.15)
				)
				(justify mirror)
			)
		)
		(sheetname "/SFP/")
		(sheetfile "sfp.kicad_sch")
		(attr smd)
		(fp_poly
			(pts
				(xy -0.925 0.47) (xy 0.925 0.47) (xy 0.925 -0.47) (xy -0.925 -0.47)
			)
			(stroke
				(width 0.05)
				(type default)
			)
			(fill no)
			(layer "B.CrtYd")
		)
		(fp_poly
			(pts
				(xy -0.5 0.25) (xy 0.5 0.25) (xy 0.5 -0.25) (xy -0.5 -0.25)
			)
			(stroke
				(width 0.15)
				(type solid)
			)
			(fill no)
			(layer "B.Fab")
		)
		(fp_text user "Author: Antmicro"
			(at -0.95 -4.169 0)
			(layer "B.Fab")
			(effects
				(font
					(size 0.7 0.7)
					(thickness 0.15)
				)
				(justify right top mirror)
			)
		)
		(fp_text user "${REFERENCE}"
			(at -0.95 -3.168 0)
			(layer "B.Fab")
			(effects
				(font
					(size 0.7 0.7)
					(thickness 0.15)
				)
				(justify right top mirror)
			)
		)
		(fp_text user "License: Apache-2.0"
			(at -0.949999 -5.169 0)
			(layer "B.Fab")
			(effects
				(font
					(size 0.7 0.7)
					(thickness 0.15)
				)
				(justify right top mirror)
			)
		)
		(pad "1" smd roundrect
			(at -0.48 0)
			(size 0.59 0.64)
			(layers "B.Cu" "B.Mask" "B.Paste")
			(roundrect_rratio 0.25)
			(net 1 "GND")
			(pintype "passive")
		)
		(pad "2" smd roundrect
			(at 0.48 0)
			(size 0.59 0.64)
			(layers "B.Cu" "B.Mask" "B.Paste")
			(roundrect_rratio 0.25)
			(net 379 "/SFP/SH")
			(pintype "passive")
		)
	)
)
